(kicad_pcb
	(version 20260206)
	(generator "pcbnew")
	(generator_version "10.0")
	(general
		(thickness 1.6)
		(legacy_teardrops no)
	)
	(paper "A4")
	(title_block
		(title "m-2 — Lightning_M.2_BRD.brd")
		(comment 1 "Lightning (Wiwynn / Facebook NVMe JBOF) / footprints 154-157 of 157")
	)
	(layers
		(0 "F.Cu" signal "TOP")
		(4 "In1.Cu" signal "L2GND")
		(6 "In2.Cu" signal "L3")
		(8 "In3.Cu" signal "L4GND")
		(10 "In4.Cu" signal "L5GND")
		(12 "In5.Cu" signal "L6")
		(14 "In6.Cu" signal "L7GND")
		(2 "B.Cu" signal "BOTTOM")
		(9 "F.Adhes" user "F.Adhesive")
		(11 "B.Adhes" user "B.Adhesive")
		(13 "F.Paste" user "Package Geometry/Pastemask Top")
		(15 "B.Paste" user "Package Geometry/Pastemask Bottom")
		(5 "F.SilkS" user "Ref Des/Silkscreen Top")
		(7 "B.SilkS" user "Ref Des/Silkscreen Bottom")
		(1 "F.Mask" user "Board Geometry/Soldermask Top")
		(3 "B.Mask" user "Board Geometry/Soldermask Bottom")
		(17 "Dwgs.User" user "User.Drawings")
		(19 "Cmts.User" user "User.Comments")
		(21 "Eco1.User" user "User.Eco1")
		(23 "Eco2.User" user "User.Eco2")
		(25 "Edge.Cuts" user "Board Geometry/Outline")
		(27 "Margin" user)
		(31 "F.CrtYd" user "Package Geometry/Place Bound Top")
		(29 "B.CrtYd" user "Package Geometry/Place Bound Bottom")
		(35 "F.Fab" user "Ref Des/Assembly Top")
		(33 "B.Fab" user "Ref Des/Assembly Bottom")
	)
	(footprint ""
		(layer "B.Cu")
		(at 69.342 -33.401 -90)
		(property "Reference" "R15"
			(at 0 0 90)
			(layer "B.SilkS")
			(hide yes)
			(effects
				(font
					(size 1.27 1.27)
				)
				(justify mirror)
			)
		)
		(property "Value" "0R2J-2-GP"
			(at -0.064008 -3.993896 270)
			(unlocked yes)
			(layer "B.Fab")
			(hide yes)
			(effects
				(font
					(size 1.016 1.016)
					(thickness 0.1524)
				)
				(justify mirror)
			)
		)
		(property "Device Type" "R402H16"
			(at -0.064008 -5.517896 270)
			(unlocked yes)
			(layer "B.Fab")
			(hide yes)
			(effects
				(font
					(size 1.016 1.016)
					(thickness 0.1524)
				)
				(justify mirror)
			)
		)
		(duplicate_pad_numbers_are_jumpers no)
		(fp_line
			(start -0.508 -0.9398)
			(end 0.508 -0.9398)
			(stroke
				(width 0.1524)
				(type default)
			)
			(layer "B.SilkS")
		)
		(fp_line
			(start 0.508 -0.9398)
			(end 0.508 0.9398)
			(stroke
				(width 0.1524)
				(type default)
			)
			(layer "B.SilkS")
		)
		(fp_rect
			(start 0.508 0.9398)
			(end -0.508 -0.9398)
			(stroke
				(width 0)
				(type default)
			)
			(fill no)
			(layer "B.CrtYd")
		)
		(fp_rect
			(start 0.508 0.9398)
			(end -0.508 -0.9398)
			(stroke
				(width 0)
				(type default)
			)
			(fill no)
			(layer "B.Fab")
		)
		(pad "1" smd custom
			(at 0 -0.4445 90)
			(size 0.1397 0.1397)
			(layers "B.Cu" "B.Mask" "B.Paste")
			(net "Z50_SSD_B_ACT#")
			(options
				(clearance outline)
				(anchor circle)
			)
			(primitives
				(gr_poly
					(pts
						(arc
							(start -0.1778 0.2794)
							(mid -0.249642 0.249642)
							(end -0.2794 0.1778)
						)
						(arc
							(start -0.2794 -0.1778)
							(mid -0.249642 -0.249642)
							(end -0.1778 -0.2794)
						)
						(arc
							(start 0.1778 -0.2794)
							(mid 0.249642 -0.249642)
							(end 0.2794 -0.1778)
						)
						(arc
							(start 0.2794 0.1778)
							(mid 0.249642 0.249642)
							(end 0.1778 0.2794)
						)
					)
					(width 0)
					(fill yes)
				)
			)
		)
		(pad "2" smd custom
			(at 0 0.4445 90)
			(size 0.1397 0.1397)
			(layers "B.Cu" "B.Mask" "B.Paste")
			(net "Z50_SSD_B_R_ACT#")
			(options
				(clearance outline)
				(anchor circle)
			)
			(primitives
				(gr_poly
					(pts
						(arc
							(start -0.1778 0.2794)
							(mid -0.249642 0.249642)
							(end -0.2794 0.1778)
						)
						(arc
							(start -0.2794 -0.1778)
							(mid -0.249642 -0.249642)
							(end -0.1778 -0.2794)
						)
						(arc
							(start 0.1778 -0.2794)
							(mid 0.249642 -0.249642)
							(end 0.2794 -0.1778)
						)
						(arc
							(start 0.2794 0.1778)
							(mid 0.249642 0.249642)
							(end 0.1778 0.2794)
						)
					)
					(width 0)
					(fill yes)
				)
			)
		)
	)
	(footprint ""
		(layer "B.Cu")
		(at 67.691 -60.579 180)
		(property "Reference" "R14"
			(at 0 0 0)
			(layer "B.SilkS")
			(hide yes)
			(effects
				(font
					(size 1.27 1.27)
				)
				(justify mirror)
			)
		)
		(property "Value" "0R2J-2-GP"
			(at -0.064008 -3.993896 180)
			(unlocked yes)
			(layer "B.Fab")
			(hide yes)
			(effects
				(font
					(size 1.016 1.016)
					(thickness 0.1524)
				)
				(justify mirror)
			)
		)
		(property "Device Type" "R402H16"
			(at -0.064008 -5.517896 180)
			(unlocked yes)
			(layer "B.Fab")
			(hide yes)
			(effects
				(font
					(size 1.016 1.016)
					(thickness 0.1524)
				)
				(justify mirror)
			)
		)
		(duplicate_pad_numbers_are_jumpers no)
		(fp_line
			(start 0.508 -0.9398)
			(end 0.508 0.9398)
			(stroke
				(width 0.1524)
				(type default)
			)
			(layer "B.SilkS")
		)
		(fp_line
			(start -0.508 -0.9398)
			(end 0.508 -0.9398)
			(stroke
				(width 0.1524)
				(type default)
			)
			(layer "B.SilkS")
		)
		(fp_rect
			(start 0.508 0.9398)
			(end -0.508 -0.9398)
			(stroke
				(width 0)
				(type default)
			)
			(fill no)
			(layer "B.CrtYd")
		)
		(fp_rect
			(start 0.508 0.9398)
			(end -0.508 -0.9398)
			(stroke
				(width 0)
				(type default)
			)
			(fill no)
			(layer "B.Fab")
		)
		(pad "1" smd custom
			(at 0 -0.4445)
			(size 0.1397 0.1397)
			(layers "B.Cu" "B.Mask" "B.Paste")
			(net "Z50_SSD_A_ACT#")
			(options
				(clearance outline)
				(anchor circle)
			)
			(primitives
				(gr_poly
					(pts
						(arc
							(start -0.1778 0.2794)
							(mid -0.249642 0.249642)
							(end -0.2794 0.1778)
						)
						(arc
							(start -0.2794 -0.1778)
							(mid -0.249642 -0.249642)
							(end -0.1778 -0.2794)
						)
						(arc
							(start 0.1778 -0.2794)
							(mid 0.249642 -0.249642)
							(end 0.2794 -0.1778)
						)
						(arc
							(start 0.2794 0.1778)
							(mid 0.249642 0.249642)
							(end 0.1778 0.2794)
						)
					)
					(width 0)
					(fill yes)
				)
			)
		)
		(pad "2" smd custom
			(at 0 0.4445)
			(size 0.1397 0.1397)
			(layers "B.Cu" "B.Mask" "B.Paste")
			(net "Z50_SSD_A_R_ACT#")
			(options
				(clearance outline)
				(anchor circle)
			)
			(primitives
				(gr_poly
					(pts
						(arc
							(start -0.1778 0.2794)
							(mid -0.249642 0.249642)
							(end -0.2794 0.1778)
						)
						(arc
							(start -0.2794 -0.1778)
							(mid -0.249642 -0.249642)
							(end -0.1778 -0.2794)
						)
						(arc
							(start 0.1778 -0.2794)
							(mid 0.249642 -0.249642)
							(end 0.2794 -0.1778)
						)
						(arc
							(start 0.2794 0.1778)
							(mid 0.249642 0.249642)
							(end 0.1778 0.2794)
						)
					)
					(width 0)
					(fill yes)
				)
			)
		)
	)
	(footprint ""
		(layer "B.Cu")
		(at 27.94 -71.755 180)
		(property "Reference" "R29"
			(at 0 0 0)
			(layer "B.SilkS")
			(hide yes)
			(effects
				(font
					(size 1.27 1.27)
				)
				(justify mirror)
			)
		)
		(property "Value" "47KR2F-GP"
			(at -0.064008 -3.993896 180)
			(unlocked yes)
			(layer "B.Fab")
			(hide yes)
			(effects
				(font
					(size 1.016 1.016)
					(thickness 0.1524)
				)
				(justify mirror)
			)
		)
		(property "Device Type" "R402H16"
			(at -0.064008 -5.517896 180)
			(unlocked yes)
			(layer "B.Fab")
			(hide yes)
			(effects
				(font
					(size 1.016 1.016)
					(thickness 0.1524)
				)
				(justify mirror)
			)
		)
		(duplicate_pad_numbers_are_jumpers no)
		(fp_line
			(start 0.508 -0.9398)
			(end 0.508 0.9398)
			(stroke
				(width 0.1524)
				(type default)
			)
			(layer "B.SilkS")
		)
		(fp_line
			(start -0.508 -0.9398)
			(end 0.508 -0.9398)
			(stroke
				(width 0.1524)
				(type default)
			)
			(layer "B.SilkS")
		)
		(fp_rect
			(start 0.508 0.9398)
			(end -0.508 -0.9398)
			(stroke
				(width 0)
				(type default)
			)
			(fill no)
			(layer "B.CrtYd")
		)
		(fp_rect
			(start 0.508 0.9398)
			(end -0.508 -0.9398)
			(stroke
				(width 0)
				(type default)
			)
			(fill no)
			(layer "B.Fab")
		)
		(pad "1" smd custom
			(at 0 -0.4445)
			(size 0.1397 0.1397)
			(layers "B.Cu" "B.Mask" "B.Paste")
			(net "Z50_SSD_B1_SMB_CLK")
			(options
				(clearance outline)
				(anchor circle)
			)
			(primitives
				(gr_poly
					(pts
						(arc
							(start -0.1778 0.2794)
							(mid -0.249642 0.249642)
							(end -0.2794 0.1778)
						)
						(arc
							(start -0.2794 -0.1778)
							(mid -0.249642 -0.249642)
							(end -0.1778 -0.2794)
						)
						(arc
							(start 0.1778 -0.2794)
							(mid 0.249642 -0.249642)
							(end 0.2794 -0.1778)
						)
						(arc
							(start 0.2794 0.1778)
							(mid 0.249642 0.249642)
							(end 0.1778 0.2794)
						)
					)
					(width 0)
					(fill yes)
				)
			)
		)
		(pad "2" smd custom
			(at 0 0.4445)
			(size 0.1397 0.1397)
			(layers "B.Cu" "B.Mask" "B.Paste")
			(net "P1V8_PWR")
			(options
				(clearance outline)
				(anchor circle)
			)
			(primitives
				(gr_poly
					(pts
						(arc
							(start -0.1778 0.2794)
							(mid -0.249642 0.249642)
							(end -0.2794 0.1778)
						)
						(arc
							(start -0.2794 -0.1778)
							(mid -0.249642 -0.249642)
							(end -0.1778 -0.2794)
						)
						(arc
							(start 0.1778 -0.2794)
							(mid 0.249642 -0.249642)
							(end 0.2794 -0.1778)
						)
						(arc
							(start 0.2794 0.1778)
							(mid 0.249642 0.249642)
							(end 0.1778 0.2794)
						)
					)
					(width 0)
					(fill yes)
				)
			)
		)
	)
	(footprint ""
		(layer "B.Cu")
		(at 25.019 -80.518 -90)
		(property "Reference" "R27"
			(at 0 0 90)
			(layer "B.SilkS")
			(hide yes)
			(effects
				(font
					(size 1.27 1.27)
				)
				(justify mirror)
			)
		)
		(property "Value" "4K7R2F-GP"
			(at -0.064008 -3.993896 270)
			(unlocked yes)
			(layer "B.Fab")
			(hide yes)
			(effects
				(font
					(size 1.016 1.016)
					(thickness 0.1524)
				)
				(justify mirror)
			)
		)
		(property "Device Type" "R402H16"
			(at -0.064008 -5.517896 270)
			(unlocked yes)
			(layer "B.Fab")
			(hide yes)
			(effects
				(font
					(size 1.016 1.016)
					(thickness 0.1524)
				)
				(justify mirror)
			)
		)
		(duplicate_pad_numbers_are_jumpers no)
		(fp_line
			(start -0.508 -0.9398)
			(end 0.508 -0.9398)
			(stroke
				(width 0.1524)
				(type default)
			)
			(layer "B.SilkS")
		)
		(fp_line
			(start 0.508 -0.9398)
			(end 0.508 0.9398)
			(stroke
				(width 0.1524)
				(type default)
			)
			(layer "B.SilkS")
		)
		(fp_rect
			(start 0.508 0.9398)
			(end -0.508 -0.9398)
			(stroke
				(width 0)
				(type default)
			)
			(fill no)
			(layer "B.CrtYd")
		)
		(fp_rect
			(start 0.508 0.9398)
			(end -0.508 -0.9398)
			(stroke
				(width 0)
				(type default)
			)
			(fill no)
			(layer "B.Fab")
		)
		(pad "1" smd custom
			(at 0 -0.4445 90)
			(size 0.1397 0.1397)
			(layers "B.Cu" "B.Mask" "B.Paste")
			(net "Z50_SMB_SWITCH_ADDRESS_A0")
			(options
				(clearance outline)
				(anchor circle)
			)
			(primitives
				(gr_poly
					(pts
						(arc
							(start -0.1778 0.2794)
							(mid -0.249642 0.249642)
							(end -0.2794 0.1778)
						)
						(arc
							(start -0.2794 -0.1778)
							(mid -0.249642 -0.249642)
							(end -0.1778 -0.2794)
						)
						(arc
							(start 0.1778 -0.2794)
							(mid 0.249642 -0.249642)
							(end 0.2794 -0.1778)
						)
						(arc
							(start 0.2794 0.1778)
							(mid 0.249642 0.249642)
							(end 0.1778 0.2794)
						)
					)
					(width 0)
					(fill yes)
				)
			)
		)
		(pad "2" smd custom
			(at 0 0.4445 90)
			(size 0.1397 0.1397)
			(layers "B.Cu" "B.Mask" "B.Paste")
			(net "GND")
			(options
				(clearance outline)
				(anchor circle)
			)
			(primitives
				(gr_poly
					(pts
						(arc
							(start -0.1778 0.2794)
							(mid -0.249642 0.249642)
							(end -0.2794 0.1778)
						)
						(arc
							(start -0.2794 -0.1778)
							(mid -0.249642 -0.249642)
							(end -0.1778 -0.2794)
						)
						(arc
							(start 0.1778 -0.2794)
							(mid 0.249642 -0.249642)
							(end 0.2794 -0.1778)
						)
						(arc
							(start 0.2794 0.1778)
							(mid 0.249642 0.249642)
							(end 0.1778 0.2794)
						)
					)
					(width 0)
					(fill yes)
				)
			)
		)
	)
)
